(kicad_pcb
	(version 20260206)
	(generator "pcbnew")
	(generator_version "10.0")
	(general
		(thickness 1.6)
		(legacy_teardrops no)
	)
	(paper "A4")
	(title_block
		(title "04192023_DAF0TMB3IC0_F0TG_MB_C_brd_V02_OCP.brd")
		(comment 1 "Grand Teton / footprints 1490-1495 of 8354")
	)
	(layers
		(0 "F.Cu" signal "TOP")
		(4 "In1.Cu" signal "GND")
		(6 "In2.Cu" signal "IN1")
		(8 "In3.Cu" signal "GND1")
		(10 "In4.Cu" signal "IN2")
		(12 "In5.Cu" signal "GND2")
		(14 "In6.Cu" signal "IN3")
		(16 "In7.Cu" signal "GND3")
		(18 "In8.Cu" signal "VCC")
		(20 "In9.Cu" signal "VCC1")
		(22 "In10.Cu" signal "GND4")
		(24 "In11.Cu" signal "IN4")
		(26 "In12.Cu" signal "GND5")
		(28 "In13.Cu" signal "IN5")
		(30 "In14.Cu" signal "GND6")
		(32 "In15.Cu" signal "IN6")
		(34 "In16.Cu" signal "GND7")
		(2 "B.Cu" signal "BOTTOM")
		(9 "F.Adhes" user "F.Adhesive")
		(11 "B.Adhes" user "B.Adhesive")
		(13 "F.Paste" user "Package Geometry/Pastemask Top")
		(15 "B.Paste" user "Package Geometry/Pastemask Bottom")
		(5 "F.SilkS" user "Ref Des/Silkscreen Top")
		(7 "B.SilkS" user "Ref Des/Silkscreen Bottom")
		(1 "F.Mask" user "Board Geometry/Soldermask Top")
		(3 "B.Mask" user "Board Geometry/Soldermask Bottom")
		(17 "Dwgs.User" user "User.Drawings")
		(19 "Cmts.User" user "User.Comments")
		(21 "Eco1.User" user "User.Eco1")
		(23 "Eco2.User" user "User.Eco2")
		(25 "Edge.Cuts" user "Board Geometry/Outline")
		(27 "Margin" user)
		(31 "F.CrtYd" user "Package Geometry/Place Bound Top")
		(29 "B.CrtYd" user "Package Geometry/Place Bound Bottom")
		(35 "F.Fab" user "Ref Des/Assembly Top")
		(33 "B.Fab" user "Ref Des/Assembly Bottom")
	)
	(footprint ""
		(layer "F.Cu")
		(at 344.955876 -70.098412 90)
		(property "Reference" "D84"
			(at -3.934714 -0.691642 90)
			(unlocked yes)
			(layer "F.SilkS")
			(effects
				(font
					(size 0.7874 0.5842)
					(thickness 0.1524)
				)
				(justify left)
			)
		)
		(property "Value" ""
			(at 0 0 90)
			(layer "F.Fab")
			(effects
				(font
					(size 1.27 1.27)
				)
			)
		)
		(duplicate_pad_numbers_are_jumpers no)
		(fp_line
			(start 1.16078 -0.4826)
			(end 1.16078 0.4826)
			(stroke
				(width 0.1524)
				(type default)
			)
			(layer "F.SilkS")
		)
		(fp_line
			(start 1.03378 -0.4826)
			(end 1.03378 0.4826)
			(stroke
				(width 0.1524)
				(type default)
			)
			(layer "F.SilkS")
		)
		(fp_line
			(start 0.90678 -0.4826)
			(end 0.90678 0.4826)
			(stroke
				(width 0.1524)
				(type default)
			)
			(layer "F.SilkS")
		)
		(fp_line
			(start -0.64008 -0.4826)
			(end 1.16078 -0.4826)
			(stroke
				(width 0.1524)
				(type default)
			)
			(layer "F.SilkS")
		)
		(fp_line
			(start -0.79248 -0.4826)
			(end 1.03378 -0.4826)
			(stroke
				(width 0.1524)
				(type default)
			)
			(layer "F.SilkS")
		)
		(fp_line
			(start -0.89408 -0.4826)
			(end 0.90678 -0.4826)
			(stroke
				(width 0.1524)
				(type default)
			)
			(layer "F.SilkS")
		)
		(fp_line
			(start 1.16078 0.4826)
			(end -0.64008 0.4826)
			(stroke
				(width 0.1524)
				(type default)
			)
			(layer "F.SilkS")
		)
		(fp_line
			(start 1.03378 0.4826)
			(end -0.79248 0.4826)
			(stroke
				(width 0.1524)
				(type default)
			)
			(layer "F.SilkS")
		)
		(fp_line
			(start 0.90678 0.4826)
			(end -0.90678 0.4826)
			(stroke
				(width 0.1524)
				(type default)
			)
			(layer "F.SilkS")
		)
		(fp_line
			(start -0.90678 0.4826)
			(end -0.90678 -0.4699)
			(stroke
				(width 0.1524)
				(type default)
			)
			(layer "F.SilkS")
		)
		(fp_line
			(start 0.499872 -0.249936)
			(end 0.499872 0.249936)
			(stroke
				(width 0.1)
				(type default)
			)
			(layer "F.Fab")
		)
		(fp_line
			(start -0.499872 -0.249936)
			(end 0.499872 -0.249936)
			(stroke
				(width 0.1)
				(type default)
			)
			(layer "F.Fab")
		)
		(fp_line
			(start 0.499872 0.249936)
			(end -0.499872 0.249936)
			(stroke
				(width 0.1)
				(type default)
			)
			(layer "F.Fab")
		)
		(fp_line
			(start -0.499872 0.249936)
			(end -0.499872 -0.249936)
			(stroke
				(width 0.1)
				(type default)
			)
			(layer "F.Fab")
		)
		(pad "A" smd rect
			(at -0.47498 0 90)
			(size 0.6096 0.7112)
			(layers "F.Cu" "F.Mask" "F.Paste")
			(net "LED_PWRGD_PVDD11_S3_P1_R")
		)
		(pad "C" smd rect
			(at 0.47498 0 90)
			(size 0.6096 0.7112)
			(layers "F.Cu" "F.Mask" "F.Paste")
			(net "LED_PWRGD_PVDD11_S3_P1_D")
		)
	)
	(footprint ""
		(layer "F.Cu")
		(at 125.512576 -55.175658 90)
		(property "Reference" "R6111"
			(at 0 0 90)
			(layer "F.SilkS")
			(hide yes)
			(effects
				(font
					(size 1.27 1.27)
				)
			)
		)
		(property "Value" ""
			(at 0 0 90)
			(layer "F.Fab")
			(effects
				(font
					(size 1.27 1.27)
				)
			)
		)
		(duplicate_pad_numbers_are_jumpers no)
		(fp_line
			(start 0.7874 -0.4064)
			(end 0.7874 0.4064)
			(stroke
				(width 0.1524)
				(type default)
			)
			(layer "F.SilkS")
		)
		(fp_line
			(start -0.7874 -0.4064)
			(end 0.7874 -0.4064)
			(stroke
				(width 0.1524)
				(type default)
			)
			(layer "F.SilkS")
		)
		(fp_line
			(start 0.7874 0.4064)
			(end -0.7874 0.4064)
			(stroke
				(width 0.1524)
				(type default)
			)
			(layer "F.SilkS")
		)
		(fp_line
			(start -0.7874 0.4064)
			(end -0.7874 -0.4064)
			(stroke
				(width 0.1524)
				(type default)
			)
			(layer "F.SilkS")
		)
		(fp_line
			(start -0.12065 -0.305054)
			(end -0.12065 -0.2794)
			(stroke
				(width 0.1)
				(type default)
			)
			(layer "F.Fab")
		)
		(fp_line
			(start -0.67945 -0.305054)
			(end -0.12065 -0.305054)
			(stroke
				(width 0.1)
				(type default)
			)
			(layer "F.Fab")
		)
		(fp_line
			(start 0.67945 -0.3048)
			(end 0.67945 0.3048)
			(stroke
				(width 0.1)
				(type default)
			)
			(layer "F.Fab")
		)
		(fp_line
			(start 0.12065 -0.3048)
			(end 0.67945 -0.3048)
			(stroke
				(width 0.1)
				(type default)
			)
			(layer "F.Fab")
		)
		(fp_line
			(start 0.12065 -0.2794)
			(end 0.12065 -0.3048)
			(stroke
				(width 0.1)
				(type default)
			)
			(layer "F.Fab")
		)
		(fp_line
			(start -0.12065 -0.2794)
			(end 0.12065 -0.2794)
			(stroke
				(width 0.1)
				(type default)
			)
			(layer "F.Fab")
		)
		(fp_line
			(start 0.120396 0.2794)
			(end -0.12065 0.2794)
			(stroke
				(width 0.1)
				(type default)
			)
			(layer "F.Fab")
		)
		(fp_line
			(start -0.12065 0.2794)
			(end -0.12065 0.3048)
			(stroke
				(width 0.1)
				(type default)
			)
			(layer "F.Fab")
		)
		(fp_line
			(start 0.67945 0.3048)
			(end 0.120396 0.3048)
			(stroke
				(width 0.1)
				(type default)
			)
			(layer "F.Fab")
		)
		(fp_line
			(start 0.120396 0.3048)
			(end 0.120396 0.2794)
			(stroke
				(width 0.1)
				(type default)
			)
			(layer "F.Fab")
		)
		(fp_line
			(start -0.12065 0.3048)
			(end -0.67945 0.3048)
			(stroke
				(width 0.1)
				(type default)
			)
			(layer "F.Fab")
		)
		(fp_line
			(start -0.67945 0.3048)
			(end -0.67945 -0.305054)
			(stroke
				(width 0.1)
				(type default)
			)
			(layer "F.Fab")
		)
		(pad "1" smd circle
			(at -0.40005 0 90)
			(size 0 0)
			(layers "F.Cu" "F.Mask" "F.Paste")
			(net "JTAG_TDO_R1")
		)
		(pad "2" smd circle
			(at 0.40005 0 90)
			(size 0 0)
			(layers "F.Cu" "F.Mask" "F.Paste")
			(net "JTAG_TDO")
		)
	)
	(footprint ""
		(layer "F.Cu")
		(at 329.150472 -400.903694)
		(property "Reference" "L14"
			(at -2.3876 -2.969768 0)
			(unlocked yes)
			(layer "F.SilkS")
			(effects
				(font
					(size 0.7874 0.5842)
					(thickness 0.1524)
				)
				(justify left)
			)
		)
		(property "Value" ""
			(at 0 0 0)
			(layer "F.Fab")
			(effects
				(font
					(size 1.27 1.27)
				)
			)
		)
		(duplicate_pad_numbers_are_jumpers no)
		(fp_line
			(start -2.249932 -2.249932)
			(end 2.249932 -2.249932)
			(stroke
				(width 0.1524)
				(type default)
			)
			(layer "F.SilkS")
		)
		(fp_line
			(start -2.249932 -1.3843)
			(end -2.249932 -2.249932)
			(stroke
				(width 0.1524)
				(type default)
			)
			(layer "F.SilkS")
		)
		(fp_line
			(start -2.249932 2.249932)
			(end -2.249932 1.3843)
			(stroke
				(width 0.1524)
				(type default)
			)
			(layer "F.SilkS")
		)
		(fp_line
			(start 2.249932 -2.249932)
			(end 2.249932 -1.3843)
			(stroke
				(width 0.1524)
				(type default)
			)
			(layer "F.SilkS")
		)
		(fp_line
			(start 2.249932 1.3843)
			(end 2.249932 2.249932)
			(stroke
				(width 0.1524)
				(type default)
			)
			(layer "F.SilkS")
		)
		(fp_line
			(start 2.249932 2.249932)
			(end -2.249932 2.249932)
			(stroke
				(width 0.1524)
				(type default)
			)
			(layer "F.SilkS")
		)
		(fp_line
			(start -2.249932 -2.249932)
			(end 2.249932 -2.249932)
			(stroke
				(width 0.1)
				(type default)
			)
			(layer "F.Fab")
		)
		(fp_line
			(start -2.249932 2.249932)
			(end -2.249932 -2.249932)
			(stroke
				(width 0.1)
				(type default)
			)
			(layer "F.Fab")
		)
		(fp_line
			(start 2.249932 -2.249932)
			(end 2.249932 2.249932)
			(stroke
				(width 0.1)
				(type default)
			)
			(layer "F.Fab")
		)
		(fp_line
			(start 2.249932 2.249932)
			(end -2.249932 2.249932)
			(stroke
				(width 0.1)
				(type default)
			)
			(layer "F.Fab")
		)
		(pad "1" smd rect
			(at -1.82499 0)
			(size 1.0668 2.5146)
			(layers "F.Cu" "F.Mask" "F.Paste")
			(net "P0V9_CPU0_RT_2D")
		)
		(pad "2" smd rect
			(at 1.82499 0)
			(size 1.0668 2.5146)
			(layers "F.Cu" "F.Mask" "F.Paste")
			(net "P0V9_CPU0_RT1_2A")
		)
	)
	(footprint ""
		(layer "F.Cu")
		(at 347.4593 -15.979394 90)
		(property "Reference" "R1208"
			(at 0 0 90)
			(layer "F.SilkS")
			(hide yes)
			(effects
				(font
					(size 1.27 1.27)
				)
			)
		)
		(property "Value" ""
			(at 0 0 90)
			(layer "F.Fab")
			(effects
				(font
					(size 1.27 1.27)
				)
			)
		)
		(duplicate_pad_numbers_are_jumpers no)
		(fp_line
			(start 0.7874 -0.4064)
			(end 0.7874 0.4064)
			(stroke
				(width 0.1524)
				(type default)
			)
			(layer "F.SilkS")
		)
		(fp_line
			(start -0.7874 -0.4064)
			(end 0.7874 -0.4064)
			(stroke
				(width 0.1524)
				(type default)
			)
			(layer "F.SilkS")
		)
		(fp_line
			(start 0.7874 0.4064)
			(end -0.7874 0.4064)
			(stroke
				(width 0.1524)
				(type default)
			)
			(layer "F.SilkS")
		)
		(fp_line
			(start -0.7874 0.4064)
			(end -0.7874 -0.4064)
			(stroke
				(width 0.1524)
				(type default)
			)
			(layer "F.SilkS")
		)
		(fp_line
			(start -0.12065 -0.305054)
			(end -0.12065 -0.2794)
			(stroke
				(width 0.1)
				(type default)
			)
			(layer "F.Fab")
		)
		(fp_line
			(start -0.67945 -0.305054)
			(end -0.12065 -0.305054)
			(stroke
				(width 0.1)
				(type default)
			)
			(layer "F.Fab")
		)
		(fp_line
			(start 0.67945 -0.3048)
			(end 0.67945 0.3048)
			(stroke
				(width 0.1)
				(type default)
			)
			(layer "F.Fab")
		)
		(fp_line
			(start 0.12065 -0.3048)
			(end 0.67945 -0.3048)
			(stroke
				(width 0.1)
				(type default)
			)
			(layer "F.Fab")
		)
		(fp_line
			(start 0.12065 -0.2794)
			(end 0.12065 -0.3048)
			(stroke
				(width 0.1)
				(type default)
			)
			(layer "F.Fab")
		)
		(fp_line
			(start -0.12065 -0.2794)
			(end 0.12065 -0.2794)
			(stroke
				(width 0.1)
				(type default)
			)
			(layer "F.Fab")
		)
		(fp_line
			(start 0.120396 0.2794)
			(end -0.12065 0.2794)
			(stroke
				(width 0.1)
				(type default)
			)
			(layer "F.Fab")
		)
		(fp_line
			(start -0.12065 0.2794)
			(end -0.12065 0.3048)
			(stroke
				(width 0.1)
				(type default)
			)
			(layer "F.Fab")
		)
		(fp_line
			(start 0.67945 0.3048)
			(end 0.120396 0.3048)
			(stroke
				(width 0.1)
				(type default)
			)
			(layer "F.Fab")
		)
		(fp_line
			(start 0.120396 0.3048)
			(end 0.120396 0.2794)
			(stroke
				(width 0.1)
				(type default)
			)
			(layer "F.Fab")
		)
		(fp_line
			(start -0.12065 0.3048)
			(end -0.67945 0.3048)
			(stroke
				(width 0.1)
				(type default)
			)
			(layer "F.Fab")
		)
		(fp_line
			(start -0.67945 0.3048)
			(end -0.67945 -0.305054)
			(stroke
				(width 0.1)
				(type default)
			)
			(layer "F.Fab")
		)
		(pad "1" smd circle
			(at -0.40005 0 90)
			(size 0 0)
			(layers "F.Cu" "F.Mask" "F.Paste")
			(net "PU_P12V_ALL_PWROK_LED")
		)
		(pad "2" smd circle
			(at 0.40005 0 90)
			(size 0 0)
			(layers "F.Cu" "F.Mask" "F.Paste")
			(net "P5V_AUX")
		)
	)
	(footprint ""
		(layer "F.Cu")
		(at 157.88259 -95.517208 90)
		(property "Reference" "R3304"
			(at 0 0 90)
			(layer "F.SilkS")
			(hide yes)
			(effects
				(font
					(size 1.27 1.27)
				)
			)
		)
		(property "Value" ""
			(at 0 0 90)
			(layer "F.Fab")
			(effects
				(font
					(size 1.27 1.27)
				)
			)
		)
		(duplicate_pad_numbers_are_jumpers no)
		(fp_line
			(start 0.7874 -0.4064)
			(end 0.7874 0.4064)
			(stroke
				(width 0.1524)
				(type default)
			)
			(layer "F.SilkS")
		)
		(fp_line
			(start -0.7874 -0.4064)
			(end 0.7874 -0.4064)
			(stroke
				(width 0.1524)
				(type default)
			)
			(layer "F.SilkS")
		)
		(fp_line
			(start 0.7874 0.4064)
			(end -0.7874 0.4064)
			(stroke
				(width 0.1524)
				(type default)
			)
			(layer "F.SilkS")
		)
		(fp_line
			(start -0.7874 0.4064)
			(end -0.7874 -0.4064)
			(stroke
				(width 0.1524)
				(type default)
			)
			(layer "F.SilkS")
		)
		(fp_line
			(start -0.12065 -0.305054)
			(end -0.12065 -0.2794)
			(stroke
				(width 0.1)
				(type default)
			)
			(layer "F.Fab")
		)
		(fp_line
			(start -0.67945 -0.305054)
			(end -0.12065 -0.305054)
			(stroke
				(width 0.1)
				(type default)
			)
			(layer "F.Fab")
		)
		(fp_line
			(start 0.67945 -0.3048)
			(end 0.67945 0.3048)
			(stroke
				(width 0.1)
				(type default)
			)
			(layer "F.Fab")
		)
		(fp_line
			(start 0.12065 -0.3048)
			(end 0.67945 -0.3048)
			(stroke
				(width 0.1)
				(type default)
			)
			(layer "F.Fab")
		)
		(fp_line
			(start 0.12065 -0.2794)
			(end 0.12065 -0.3048)
			(stroke
				(width 0.1)
				(type default)
			)
			(layer "F.Fab")
		)
		(fp_line
			(start -0.12065 -0.2794)
			(end 0.12065 -0.2794)
			(stroke
				(width 0.1)
				(type default)
			)
			(layer "F.Fab")
		)
		(fp_line
			(start 0.120396 0.2794)
			(end -0.12065 0.2794)
			(stroke
				(width 0.1)
				(type default)
			)
			(layer "F.Fab")
		)
		(fp_line
			(start -0.12065 0.2794)
			(end -0.12065 0.3048)
			(stroke
				(width 0.1)
				(type default)
			)
			(layer "F.Fab")
		)
		(fp_line
			(start 0.67945 0.3048)
			(end 0.120396 0.3048)
			(stroke
				(width 0.1)
				(type default)
			)
			(layer "F.Fab")
		)
		(fp_line
			(start 0.120396 0.3048)
			(end 0.120396 0.2794)
			(stroke
				(width 0.1)
				(type default)
			)
			(layer "F.Fab")
		)
		(fp_line
			(start -0.12065 0.3048)
			(end -0.67945 0.3048)
			(stroke
				(width 0.1)
				(type default)
			)
			(layer "F.Fab")
		)
		(fp_line
			(start -0.67945 0.3048)
			(end -0.67945 -0.305054)
			(stroke
				(width 0.1)
				(type default)
			)
			(layer "F.Fab")
		)
		(pad "1" smd circle
			(at -0.40005 0 90)
			(size 0 0)
			(layers "F.Cu" "F.Mask" "F.Paste")
			(net "OCP_SFF_PRSNT_ALL_R_N")
		)
		(pad "2" smd circle
			(at 0.40005 0 90)
			(size 0 0)
			(layers "F.Cu" "F.Mask" "F.Paste")
			(net "OCP_SFF_PRSNT_ALL_R3_N")
		)
	)
	(footprint ""
		(layer "F.Cu")
		(at 11.895836 -92.687648 -90)
		(property "Reference" "C2041"
			(at 0 0 270)
			(layer "F.SilkS")
			(hide yes)
			(effects
				(font
					(size 1.27 1.27)
				)
			)
		)
		(property "Value" ""
			(at 0 0 270)
			(layer "F.Fab")
			(effects
				(font
					(size 1.27 1.27)
				)
			)
		)
		(duplicate_pad_numbers_are_jumpers no)
		(fp_line
			(start -0.7874 0.4064)
			(end -0.7874 -0.4064)
			(stroke
				(width 0.1524)
				(type default)
			)
			(layer "F.SilkS")
		)
		(fp_line
			(start 0.7874 0.4064)
			(end -0.7874 0.4064)
			(stroke
				(width 0.1524)
				(type default)
			)
			(layer "F.SilkS")
		)
		(fp_line
			(start -0.7874 -0.4064)
			(end 0.7874 -0.4064)
			(stroke
				(width 0.1524)
				(type default)
			)
			(layer "F.SilkS")
		)
		(fp_line
			(start 0.7874 -0.4064)
			(end 0.7874 0.4064)
			(stroke
				(width 0.1524)
				(type default)
			)
			(layer "F.SilkS")
		)
		(fp_line
			(start -0.67945 0.3048)
			(end -0.67945 -0.305054)
			(stroke
				(width 0.1)
				(type default)
			)
			(layer "F.Fab")
		)
		(fp_line
			(start -0.12065 0.3048)
			(end -0.67945 0.3048)
			(stroke
				(width 0.1)
				(type default)
			)
			(layer "F.Fab")
		)
		(fp_line
			(start 0.120396 0.3048)
			(end 0.120396 0.2794)
			(stroke
				(width 0.1)
				(type default)
			)
			(layer "F.Fab")
		)
		(fp_line
			(start 0.67945 0.3048)
			(end 0.120396 0.3048)
			(stroke
				(width 0.1)
				(type default)
			)
			(layer "F.Fab")
		)
		(fp_line
			(start -0.12065 0.2794)
			(end -0.12065 0.3048)
			(stroke
				(width 0.1)
				(type default)
			)
			(layer "F.Fab")
		)
		(fp_line
			(start 0.120396 0.2794)
			(end -0.12065 0.2794)
			(stroke
				(width 0.1)
				(type default)
			)
			(layer "F.Fab")
		)
		(fp_line
			(start -0.12065 -0.2794)
			(end 0.12065 -0.2794)
			(stroke
				(width 0.1)
				(type default)
			)
			(layer "F.Fab")
		)
		(fp_line
			(start 0.12065 -0.2794)
			(end 0.12065 -0.3048)
			(stroke
				(width 0.1)
				(type default)
			)
			(layer "F.Fab")
		)
		(fp_line
			(start 0.12065 -0.3048)
			(end 0.67945 -0.3048)
			(stroke
				(width 0.1)
				(type default)
			)
			(layer "F.Fab")
		)
		(fp_line
			(start 0.67945 -0.3048)
			(end 0.67945 0.3048)
			(stroke
				(width 0.1)
				(type default)
			)
			(layer "F.Fab")
		)
		(fp_line
			(start -0.67945 -0.305054)
			(end -0.12065 -0.305054)
			(stroke
				(width 0.1)
				(type default)
			)
			(layer "F.Fab")
		)
		(fp_line
			(start -0.12065 -0.305054)
			(end -0.12065 -0.2794)
			(stroke
				(width 0.1)
				(type default)
			)
			(layer "F.Fab")
		)
		(pad "1" smd circle
			(at -0.40005 0 270)
			(size 0 0)
			(layers "F.Cu" "F.Mask" "F.Paste")
			(net "RST_USB_HUB_R_N")
		)
		(pad "2" smd circle
			(at 0.40005 0 270)
			(size 0 0)
			(layers "F.Cu" "F.Mask" "F.Paste")
			(net "GND")
		)
	)
)
